(kicad_pcb
	(version 20241229)
	(generator "pcbnew")
	(generator_version "9.0")
	(general
		(thickness 1.62)
		(legacy_teardrops no)
	)
	(paper "A3")
	(title_block
		(title "COM Express 7 Baseboard")
		(date "2025-02-04")
		(rev "1.1.2")
		(company "Antmicro Ltd")
		(comment 1 "www.antmicro.com")
		(comment 9 "footprints 687-689 of 802")
	)
	(layers
		(0 "F.Cu" signal)
		(4 "In1.Cu" signal)
		(6 "In2.Cu" signal)
		(8 "In3.Cu" signal)
		(10 "In4.Cu" signal)
		(12 "In5.Cu" signal)
		(14 "In6.Cu" signal)
		(2 "B.Cu" signal)
		(9 "F.Adhes" user "F.Adhesive")
		(11 "B.Adhes" user "B.Adhesive")
		(13 "F.Paste" user)
		(15 "B.Paste" user)
		(5 "F.SilkS" user "F.Silkscreen")
		(7 "B.SilkS" user "B.Silkscreen")
		(1 "F.Mask" user)
		(3 "B.Mask" user)
		(17 "Dwgs.User" user "User.Drawings")
		(19 "Cmts.User" user "User.Comments")
		(21 "Eco1.User" user "User.Eco1")
		(23 "Eco2.User" user "User.Eco2")
		(25 "Edge.Cuts" user)
		(27 "Margin" user)
		(31 "F.CrtYd" user "F.Courtyard")
		(29 "B.CrtYd" user "B.Courtyard")
		(35 "F.Fab" user)
		(33 "B.Fab" user)
	)
	(footprint "antmicro-footprints:R_0402_1005Metric"
		(layer "B.Cu")
		(at 198.752322 135.660843 135)
		(descr "Resistor SMD 0402")
		(tags "resistor SMD 0402")
		(property "Reference" "R215"
			(at -1.051351 0.430289 135)
			(layer "B.SilkS")
			(effects
				(font
					(size 0.7 0.7)
					(thickness 0.15)
				)
				(justify right top mirror)
			)
		)
		(property "Value" "R_0R_0402"
			(at -1.011843 -1.772046 135)
			(layer "B.Fab")
			(effects
				(font
					(size 0.7 0.7)
					(thickness 0.15)
				)
				(justify right top mirror)
			)
		)
		(property "Datasheet" "https://industrial.panasonic.com/cdbs/www-data/pdf/RDA0000/AOA0000C301.pdf"
			(at 0 0 135)
			(layer "B.Fab")
			(hide yes)
			(effects
				(font
					(size 1.27 1.27)
					(thickness 0.15)
				)
				(justify mirror)
			)
		)
		(property "Author" "Antmicro"
			(at 324.173 46.429 45)
			(layer "B.Fab")
			(hide yes)
			(effects
				(font
					(size 1 1)
					(thickness 0.15)
				)
				(justify mirror)
			)
		)
		(property "Current" "1A"
			(at 324.173 46.429 45)
			(layer "B.Fab")
			(hide yes)
			(effects
				(font
					(size 1 1)
					(thickness 0.15)
				)
				(justify mirror)
			)
		)
		(property "License" "Apache-2.0"
			(at 324.173 46.429 45)
			(layer "B.Fab")
			(hide yes)
			(effects
				(font
					(size 1 1)
					(thickness 0.15)
				)
				(justify mirror)
			)
		)
		(property "MPN" "ERJ2GE0R00X"
			(at 324.173 46.429 45)
			(layer "B.Fab")
			(hide yes)
			(effects
				(font
					(size 1 1)
					(thickness 0.15)
				)
				(justify mirror)
			)
		)
		(property "Manufacturer" "Panasonic"
			(at 324.173 46.429 45)
			(layer "B.Fab")
			(hide yes)
			(effects
				(font
					(size 1 1)
					(thickness 0.15)
				)
				(justify mirror)
			)
		)
		(property "Public" "False"
			(at 324.173 46.429 45)
			(layer "B.Fab")
			(hide yes)
			(effects
				(font
					(size 1 1)
					(thickness 0.15)
				)
				(justify mirror)
			)
		)
		(property "Tolerance" ""
			(at 324.173 46.429 45)
			(layer "B.Fab")
			(hide yes)
			(effects
				(font
					(size 1 1)
					(thickness 0.15)
				)
				(justify mirror)
			)
		)
		(property "Val" "0R"
			(at 324.173 46.429 45)
			(layer "B.Fab")
			(hide yes)
			(effects
				(font
					(size 1 1)
					(thickness 0.15)
				)
				(justify mirror)
			)
		)
		(sheetname "PCIe redriver")
		(sheetfile "pcie_redriver.kicad_sch")
		(attr smd)
		(fp_poly
			(pts
				(xy -0.925 0.47) (xy 0.925 0.47) (xy 0.925 -0.47) (xy -0.925 -0.47)
			)
			(stroke
				(width 0.05)
				(type default)
			)
			(fill no)
			(layer "B.CrtYd")
		)
		(fp_poly
			(pts
				(xy -0.5 0.25) (xy 0.5 0.25) (xy 0.5 -0.25) (xy -0.5 -0.25)
			)
			(stroke
				(width 0.15)
				(type solid)
			)
			(fill no)
			(layer "B.Fab")
		)
		(pad "1" smd roundrect
			(at -0.48 0 135)
			(size 0.59 0.64)
			(layers "B.Cu" "B.Mask" "B.Paste")
			(roundrect_rratio 0.25)
			(net 2 "+3V3")
			(pintype "passive")
			(teardrops
				(best_length_ratio 0.2)
				(max_length 1)
				(best_width_ratio 0.9)
				(max_width 2)
				(curved_edges yes)
				(filter_ratio 0.9)
				(enabled yes)
				(allow_two_segments yes)
				(prefer_zone_connections yes)
			)
		)
		(pad "2" smd roundrect
			(at 0.48 0 135)
			(size 0.59 0.64)
			(layers "B.Cu" "B.Mask" "B.Paste")
			(roundrect_rratio 0.25)
			(net 630 "Net-(U40-RXDET)")
			(pintype "passive")
			(teardrops
				(best_length_ratio 0.2)
				(max_length 1)
				(best_width_ratio 0.9)
				(max_width 2)
				(curved_edges yes)
				(filter_ratio 0.9)
				(enabled yes)
				(allow_two_segments yes)
				(prefer_zone_connections yes)
			)
		)
	)
	(footprint "antmicro-footprints:R_0402_1005Metric"
		(layer "B.Cu")
		(at 110.9 69.86 -90)
		(descr "Resistor SMD 0402")
		(tags "resistor SMD 0402")
		(property "Reference" "R73"
			(at 0.8 -0.45 90)
			(layer "B.SilkS")
			(effects
				(font
					(size 0.7 0.7)
					(thickness 0.15)
				)
				(justify left bottom mirror)
			)
		)
		(property "Value" "R_220R_0402"
			(at -1.011843 -1.772047 90)
			(layer "B.Fab")
			(effects
				(font
					(size 0.7 0.7)
					(thickness 0.15)
				)
				(justify left bottom mirror)
			)
		)
		(property "Datasheet" "https://www.bourns.com/docs/product-datasheets/cr.pdf"
			(at 0 0 270)
			(layer "F.Fab")
			(hide yes)
			(effects
				(font
					(size 1.27 1.27)
					(thickness 0.15)
				)
			)
		)
		(property "Author" "Antmicro"
			(at 41.04 180.76 0)
			(layer "B.Fab")
			(hide yes)
			(effects
				(font
					(size 1 1)
					(thickness 0.15)
				)
				(justify mirror)
			)
		)
		(property "License" "Apache-2.0"
			(at 41.04 180.76 0)
			(layer "B.Fab")
			(hide yes)
			(effects
				(font
					(size 1 1)
					(thickness 0.15)
				)
				(justify mirror)
			)
		)
		(property "MPN" "CR0402-FX-2200GLF"
			(at 41.04 180.76 0)
			(layer "B.Fab")
			(hide yes)
			(effects
				(font
					(size 1 1)
					(thickness 0.15)
				)
				(justify mirror)
			)
		)
		(property "Manufacturer" "Bourns"
			(at 41.04 180.76 0)
			(layer "B.Fab")
			(hide yes)
			(effects
				(font
					(size 1 1)
					(thickness 0.15)
				)
				(justify mirror)
			)
		)
		(property "Public" "False"
			(at 41.04 180.76 0)
			(layer "B.Fab")
			(hide yes)
			(effects
				(font
					(size 1 1)
					(thickness 0.15)
				)
				(justify mirror)
			)
		)
		(property "Tolerance" "1%"
			(at 41.04 180.76 0)
			(layer "B.Fab")
			(hide yes)
			(effects
				(font
					(size 1 1)
					(thickness 0.15)
				)
				(justify mirror)
			)
		)
		(property "Val" "220R"
			(at 41.04 180.76 0)
			(layer "B.Fab")
			(hide yes)
			(effects
				(font
					(size 1 1)
					(thickness 0.15)
				)
				(justify mirror)
			)
		)
		(sheetname "USB-C console")
		(sheetfile "usb-c_console.kicad_sch")
		(attr smd)
		(fp_rect
			(start -0.925 0.47)
			(end 0.925 -0.47)
			(stroke
				(width 0.05)
				(type default)
			)
			(fill no)
			(layer "B.CrtYd")
		)
		(fp_rect
			(start -0.5 0.25)
			(end 0.5 -0.25)
			(stroke
				(width 0.15)
				(type solid)
			)
			(fill no)
			(layer "B.Fab")
		)
		(pad "1" smd roundrect
			(at -0.48 0 270)
			(size 0.59 0.64)
			(layers "B.Cu" "B.Mask" "B.Paste")
			(roundrect_rratio 0.25)
			(net 934 "Net-(D12-A)")
			(pintype "passive")
			(teardrops
				(best_length_ratio 0.2)
				(max_length 1)
				(best_width_ratio 0.9)
				(max_width 2)
				(curved_edges yes)
				(filter_ratio 0.9)
				(enabled yes)
				(allow_two_segments yes)
				(prefer_zone_connections yes)
			)
		)
		(pad "2" smd roundrect
			(at 0.48 0 270)
			(size 0.59 0.64)
			(layers "B.Cu" "B.Mask" "B.Paste")
			(roundrect_rratio 0.25)
			(net 57 "/USB-C console/FTDI_VCCIO")
			(pintype "passive")
			(teardrops
				(best_length_ratio 0.2)
				(max_length 1)
				(best_width_ratio 0.9)
				(max_width 2)
				(curved_edges yes)
				(filter_ratio 0.9)
				(enabled yes)
				(allow_two_segments yes)
				(prefer_zone_connections yes)
			)
		)
	)
	(footprint "antmicro-footprints:R_0402_1005Metric"
		(layer "B.Cu")
		(at 121.7 160.56 180)
		(descr "Resistor SMD 0402")
		(tags "resistor SMD 0402")
		(property "Reference" "R77"
			(at -1 0.5 0)
			(layer "B.SilkS")
			(effects
				(font
					(size 0.7 0.7)
					(thickness 0.15)
				)
				(justify left bottom mirror)
			)
		)
		(property "Value" "R_0R_0402"
			(at -1.011843 -1.772047 0)
			(layer "B.Fab")
			(effects
				(font
					(size 0.7 0.7)
					(thickness 0.15)
				)
				(justify left bottom mirror)
			)
		)
		(property "Datasheet" "https://industrial.panasonic.com/cdbs/www-data/pdf/RDA0000/AOA0000C301.pdf"
			(at 0 0 180)
			(layer "F.Fab")
			(hide yes)
			(effects
				(font
					(size 1.27 1.27)
					(thickness 0.15)
				)
			)
		)
		(property "Author" "Antmicro"
			(at 243.4 321.12 0)
			(layer "B.Fab")
			(hide yes)
			(effects
				(font
					(size 1 1)
					(thickness 0.15)
				)
				(justify mirror)
			)
		)
		(property "Current" "1A"
			(at 243.4 321.12 0)
			(layer "B.Fab")
			(hide yes)
			(effects
				(font
					(size 1 1)
					(thickness 0.15)
				)
				(justify mirror)
			)
		)
		(property "License" "Apache-2.0"
			(at 243.4 321.12 0)
			(layer "B.Fab")
			(hide yes)
			(effects
				(font
					(size 1 1)
					(thickness 0.15)
				)
				(justify mirror)
			)
		)
		(property "MPN" "ERJ2GE0R00X"
			(at 243.4 321.12 0)
			(layer "B.Fab")
			(hide yes)
			(effects
				(font
					(size 1 1)
					(thickness 0.15)
				)
				(justify mirror)
			)
		)
		(property "Manufacturer" "Panasonic"
			(at 243.4 321.12 0)
			(layer "B.Fab")
			(hide yes)
			(effects
				(font
					(size 1 1)
					(thickness 0.15)
				)
				(justify mirror)
			)
		)
		(property "Public" "False"
			(at 243.4 321.12 0)
			(layer "B.Fab")
			(hide yes)
			(effects
				(font
					(size 1 1)
					(thickness 0.15)
				)
				(justify mirror)
			)
		)
		(property "Tolerance" ""
			(at 243.4 321.12 0)
			(layer "B.Fab")
			(hide yes)
			(effects
				(font
					(size 1 1)
					(thickness 0.15)
				)
				(justify mirror)
			)
		)
		(property "Val" "0R"
			(at 243.4 321.12 0)
			(layer "B.Fab")
			(hide yes)
			(effects
				(font
					(size 1 1)
					(thickness 0.15)
				)
				(justify mirror)
			)
		)
		(sheetname "OCuLink")
		(sheetfile "oculink.kicad_sch")
		(attr smd)
		(fp_rect
			(start -0.925 0.47)
			(end 0.925 -0.47)
			(stroke
				(width 0.05)
				(type default)
			)
			(fill no)
			(layer "B.CrtYd")
		)
		(fp_rect
			(start -0.5 0.25)
			(end 0.5 -0.25)
			(stroke
				(width 0.15)
				(type solid)
			)
			(fill no)
			(layer "B.Fab")
		)
		(pad "1" smd roundrect
			(at -0.48 0 180)
			(size 0.59 0.64)
			(layers "B.Cu" "B.Mask" "B.Paste")
			(roundrect_rratio 0.25)
			(net 945 "/GPIO expander/GPIOEX5")
			(pintype "passive")
			(teardrops
				(best_length_ratio 0.2)
				(max_length 1)
				(best_width_ratio 0.9)
				(max_width 2)
				(curved_edges yes)
				(filter_ratio 0.9)
				(enabled yes)
				(allow_two_segments yes)
				(prefer_zone_connections yes)
			)
		)
		(pad "2" smd roundrect
			(at 0.48 0 180)
			(size 0.59 0.64)
			(layers "B.Cu" "B.Mask" "B.Paste")
			(roundrect_rratio 0.25)
			(net 201 "/OCuLink/~{CPRSNT_D0}")
			(pintype "passive")
			(teardrops
				(best_length_ratio 0.2)
				(max_length 1)
				(best_width_ratio 0.9)
				(max_width 2)
				(curved_edges yes)
				(filter_ratio 0.9)
				(enabled yes)
				(allow_two_segments yes)
				(prefer_zone_connections yes)
			)
		)
	)
)
